(kicad_pcb
	(version 20260206)
	(generator "pcbnew")
	(generator_version "10.0")
	(general
		(thickness 1.6)
		(legacy_teardrops no)
	)
	(paper "A4")
	(title_block
		(title "pdpb — Lightning_PDPB_BRD.brd")
		(comment 1 "Lightning (Wiwynn / Facebook NVMe JBOF) / footprints 93-93 of 1140")
	)
	(layers
		(0 "F.Cu" signal "TOP")
		(4 "In1.Cu" signal "L2GND")
		(6 "In2.Cu" signal "L3")
		(8 "In3.Cu" signal "L4VCC")
		(10 "In4.Cu" signal "L5VCC")
		(12 "In5.Cu" signal "L6")
		(14 "In6.Cu" signal "L7GND")
		(2 "B.Cu" signal "BOTTOM")
		(9 "F.Adhes" user "F.Adhesive")
		(11 "B.Adhes" user "B.Adhesive")
		(13 "F.Paste" user "Package Geometry/Pastemask Top")
		(15 "B.Paste" user "Package Geometry/Pastemask Bottom")
		(5 "F.SilkS" user "Ref Des/Silkscreen Top")
		(7 "B.SilkS" user "Ref Des/Silkscreen Bottom")
		(1 "F.Mask" user "Board Geometry/Soldermask Top")
		(3 "B.Mask" user "Board Geometry/Soldermask Bottom")
		(17 "Dwgs.User" user "User.Drawings")
		(19 "Cmts.User" user "User.Comments")
		(21 "Eco1.User" user "User.Eco1")
		(23 "Eco2.User" user "User.Eco2")
		(25 "Edge.Cuts" user "Board Geometry/Outline")
		(27 "Margin" user)
		(31 "F.CrtYd" user "Package Geometry/Place Bound Top")
		(29 "B.CrtYd" user "Package Geometry/Place Bound Bottom")
		(35 "F.Fab" user "Ref Des/Assembly Top")
		(33 "B.Fab" user "Ref Des/Assembly Bottom")
	)
	(footprint ""
		(layer "F.Cu")
		(at 41.150032 -479.67011 90)
		(property "Reference" "J5"
			(at 0 0 90)
			(layer "F.SilkS")
			(hide yes)
			(effects
				(font
					(size 1.27 1.27)
				)
			)
		)
		(property "Value" "PCISLT68-14-GP-U1"
			(at -22.225 12.7508 90)
			(unlocked yes)
			(layer "F.Fab")
			(hide yes)
			(effects
				(font
					(size 1.016 1.016)
					(thickness 0.1524)
				)
			)
		)
		(property "Device Type" "SD-78827-0001"
			(at -22.225 11.2268 90)
			(unlocked yes)
			(layer "F.Fab")
			(hide yes)
			(effects
				(font
					(size 1.016 1.016)
					(thickness 0.1524)
				)
			)
		)
		(duplicate_pad_numbers_are_jumpers no)
		(fp_line
			(start 20.4724 -3.4036)
			(end 20.4724 0.0254)
			(stroke
				(width 0.1524)
				(type default)
			)
			(layer "F.SilkS")
		)
		(fp_line
			(start -20.4724 -3.4036)
			(end 20.4724 -3.4036)
			(stroke
				(width 0.1524)
				(type default)
			)
			(layer "F.SilkS")
		)
		(fp_line
			(start 23.749 0.0254)
			(end 23.749 4.6736)
			(stroke
				(width 0.1524)
				(type default)
			)
			(layer "F.SilkS")
		)
		(fp_line
			(start 20.4724 0.0254)
			(end 23.749 0.0254)
			(stroke
				(width 0.1524)
				(type default)
			)
			(layer "F.SilkS")
		)
		(fp_line
			(start -20.4724 0.0254)
			(end -20.4724 -3.4036)
			(stroke
				(width 0.1524)
				(type default)
			)
			(layer "F.SilkS")
		)
		(fp_line
			(start -23.749 0.0254)
			(end -20.4724 0.0254)
			(stroke
				(width 0.1524)
				(type default)
			)
			(layer "F.SilkS")
		)
		(fp_line
			(start 23.117556 1.803908)
			(end 23.117556 2.896108)
			(stroke
				(width 0.3048)
				(type default)
			)
			(layer "F.SilkS")
		)
		(fp_line
			(start -20.882356 1.803908)
			(end -20.882356 2.896108)
			(stroke
				(width 0.3048)
				(type default)
			)
			(layer "F.SilkS")
		)
		(fp_line
			(start 20.882356 2.896108)
			(end 20.882356 1.803908)
			(stroke
				(width 0.3048)
				(type default)
			)
			(layer "F.SilkS")
		)
		(fp_line
			(start -23.117556 2.896108)
			(end -23.117556 1.803908)
			(stroke
				(width 0.3048)
				(type default)
			)
			(layer "F.SilkS")
		)
		(fp_line
			(start 23.749 4.6736)
			(end 20.4724 4.6736)
			(stroke
				(width 0.1524)
				(type default)
			)
			(layer "F.SilkS")
		)
		(fp_line
			(start 20.4724 4.6736)
			(end 20.4724 12.0142)
			(stroke
				(width 0.1524)
				(type default)
			)
			(layer "F.SilkS")
		)
		(fp_line
			(start -20.4724 4.6736)
			(end -23.749 4.6736)
			(stroke
				(width 0.1524)
				(type default)
			)
			(layer "F.SilkS")
		)
		(fp_line
			(start -23.749 4.6736)
			(end -23.749 0.0254)
			(stroke
				(width 0.1524)
				(type default)
			)
			(layer "F.SilkS")
		)
		(fp_line
			(start 17.8435 10.3124)
			(end -17.8435 10.3124)
			(stroke
				(width 0.1524)
				(type default)
			)
			(layer "F.SilkS")
		)
		(fp_line
			(start -17.8435 10.3124)
			(end -17.8435 12.0142)
			(stroke
				(width 0.1524)
				(type default)
			)
			(layer "F.SilkS")
		)
		(fp_line
			(start 20.4724 12.0142)
			(end 17.8435 12.0142)
			(stroke
				(width 0.1524)
				(type default)
			)
			(layer "F.SilkS")
		)
		(fp_line
			(start 17.8435 12.0142)
			(end 17.8435 10.3124)
			(stroke
				(width 0.1524)
				(type default)
			)
			(layer "F.SilkS")
		)
		(fp_line
			(start -17.8435 12.0142)
			(end -20.4724 12.0142)
			(stroke
				(width 0.1524)
				(type default)
			)
			(layer "F.SilkS")
		)
		(fp_line
			(start -20.4724 12.0142)
			(end -20.4724 4.6736)
			(stroke
				(width 0.1524)
				(type default)
			)
			(layer "F.SilkS")
		)
		(fp_arc
			(start 20.882356 1.803908)
			(mid 21.999956 0.686308)
			(end 23.117556 1.803908)
			(stroke
				(width 0.3048)
				(type default)
			)
			(layer "F.SilkS")
		)
		(fp_arc
			(start -23.117556 1.803908)
			(mid -21.999956 0.686308)
			(end -20.882356 1.803908)
			(stroke
				(width 0.3048)
				(type default)
			)
			(layer "F.SilkS")
		)
		(fp_arc
			(start 23.117556 2.896108)
			(mid 21.999956 4.013708)
			(end 20.882356 2.896108)
			(stroke
				(width 0.3048)
				(type default)
			)
			(layer "F.SilkS")
		)
		(fp_arc
			(start -20.882356 2.896108)
			(mid -21.999956 4.013708)
			(end -23.117556 2.896108)
			(stroke
				(width 0.3048)
				(type default)
			)
			(layer "F.SilkS")
		)
		(fp_poly
			(pts
				(xy -20.2184 11.7602) (xy -20.2184 4.4196) (xy -23.495 4.4196) (xy -23.495 0.2794) (xy -20.2184 0.2794)
				(xy -20.2184 -3.1496) (xy 20.2184 -3.1496) (xy 20.2184 0.2794) (xy 23.495 0.2794) (xy 23.495 4.4196)
				(xy 20.2184 4.4196) (xy 20.2184 11.7602) (xy 18.0975 11.7602) (xy 18.0975 10.0584) (xy -18.0975 10.0584)
				(xy -18.0975 11.7602)
			)
			(stroke
				(width 0)
				(type default)
			)
			(fill no)
			(layer "F.CrtYd")
		)
		(fp_poly
			(pts
				(xy -21.2471 16.256) (xy -21.2471 4.9276) (xy -24.003 4.9276) (xy -24.003 -0.2286) (xy -20.7264 -0.2286)
				(xy -20.7264 -3.6576) (xy 20.7264 -3.6576) (xy 20.7264 -0.2286) (xy 24.003 -0.2286) (xy 24.003 -0.00635)
				(xy 20.2184 -0.00635) (xy 20.2184 -3.1496) (xy -20.2184 -3.1496) (xy -20.2184 0.2794) (xy -23.495 0.2794)
				(xy -23.495 4.4196) (xy -20.2184 4.4196) (xy -20.2184 11.7602) (xy -18.0975 11.7602) (xy -18.0975 10.0584)
				(xy 18.0975 10.0584) (xy 18.0975 11.7602) (xy 20.2184 11.7602) (xy 20.2184 4.4196) (xy 23.495 4.4196)
				(xy 23.495 0.2794) (xy 20.2184 0.2794) (xy 20.2184 0.00635) (xy 24.003 0.00635) (xy 24.003 4.9276)
				(xy 21.2471 4.9276) (xy 21.2471 16.256)
			)
			(stroke
				(width 0)
				(type default)
			)
			(fill no)
			(layer "F.CrtYd")
		)
		(fp_poly
			(pts
				(xy -21.2471 16.256) (xy -21.2471 4.9276) (xy -24.003 4.9276) (xy -24.003 -0.2286) (xy -20.7264 -0.2286)
				(xy -20.7264 -3.6576) (xy 20.7264 -3.6576) (xy 20.7264 -0.2286) (xy 24.003 -0.2286) (xy 24.003 4.9276)
				(xy 21.2471 4.9276) (xy 21.2471 16.256)
			)
			(stroke
				(width 0)
				(type default)
			)
			(fill no)
			(layer "F.Fab")
		)
		(pad "" np_thru_hole circle
			(at -18.999962 0 90)
			(size 0.254 0.254)
			(drill 1.8542)
			(layers "*.Cu" "*.Mask")
			(clearance 1.1557)
			(thermal_gap 1.1557)
		)
		(pad "" np_thru_hole circle
			(at 18.999962 0 90)
			(size 0.254 0.254)
			(drill 1.8542)
			(layers "*.Cu" "*.Mask")
			(clearance 1.1557)
			(thermal_gap 1.1557)
		)
		(pad "E1" smd rect
			(at -7.079996 1.240028 90)
			(size 0.508 2.0066)
			(layers "F.Cu" "F.Mask" "F.Paste")
			(net "PE_CLK100M_DR5_2_P")
		)
		(pad "E2" smd rect
			(at -6.279896 1.240028 90)
			(size 0.508 2.0066)
			(layers "F.Cu" "F.Mask" "F.Paste")
			(net "PE_CLK100M_DR5_2_N")
		)
		(pad "E3" smd rect
			(at -5.48005 1.240028 90)
			(size 0.508 2.0066)
			(layers "F.Cu" "F.Mask" "F.Paste")
			(net "P3V3")
		)
		(pad "E4" smd rect
			(at -4.67995 1.240028 90)
			(size 0.508 2.0066)
			(layers "F.Cu" "F.Mask" "F.Paste")
			(net "SSD5_PERST_N")
		)
		(pad "E5" smd rect
			(at -3.880104 1.240028 90)
			(size 0.508 2.0066)
			(layers "F.Cu" "F.Mask" "F.Paste")
			(net "SSD5_PERST_N")
		)
		(pad "E6" smd rect
			(at -3.080004 1.240028 90)
			(size 0.508 2.0066)
			(layers "F.Cu" "F.Mask" "F.Paste")
			(net "Net_1143")
		)
		(pad "E7" smd rect
			(at -15.48003 -1.949958 90)
			(size 0.508 2.0066)
			(layers "F.Cu" "F.Mask" "F.Paste")
			(net "PE_CLK100M_DR5_1_P")
		)
		(pad "E8" smd rect
			(at -14.67993 -1.949958 90)
			(size 0.508 2.0066)
			(layers "F.Cu" "F.Mask" "F.Paste")
			(net "PE_CLK100M_DR5_1_N")
		)
		(pad "E9" smd rect
			(at -13.880084 -1.949958 90)
			(size 0.508 2.0066)
			(layers "F.Cu" "F.Mask" "F.Paste")
			(net "GND")
		)
		(pad "E10" smd rect
			(at -13.079984 -1.949958 90)
			(size 0.508 2.0066)
			(layers "F.Cu" "F.Mask" "F.Paste")
			(net "PE_TX1_DR5_P")
		)
		(pad "E11" smd rect
			(at -12.279884 -1.949958 90)
			(size 0.508 2.0066)
			(layers "F.Cu" "F.Mask" "F.Paste")
			(net "PE_TX1_DR5_N")
		)
		(pad "E12" smd rect
			(at -11.480038 -1.949958 90)
			(size 0.508 2.0066)
			(layers "F.Cu" "F.Mask" "F.Paste")
			(net "GND")
		)
		(pad "E13" smd rect
			(at -10.679938 -1.949958 90)
			(size 0.508 2.0066)
			(layers "F.Cu" "F.Mask" "F.Paste")
			(net "PE_RX1_DR5_P")
		)
		(pad "E14" smd rect
			(at -9.880092 -1.949958 90)
			(size 0.508 2.0066)
			(layers "F.Cu" "F.Mask" "F.Paste")
			(net "PE_RX1_DR5_N")
		)
		(pad "E15" smd rect
			(at -9.079992 -1.949958 90)
			(size 0.508 2.0066)
			(layers "F.Cu" "F.Mask" "F.Paste")
			(net "GND")
		)
		(pad "E16" smd rect
			(at -8.279892 -1.949958 90)
			(size 0.508 2.0066)
			(layers "F.Cu" "F.Mask" "F.Paste")
			(net "Net_1150")
		)
		(pad "E17" smd rect
			(at 9.320022 -1.949958 90)
			(size 0.508 2.0066)
			(layers "F.Cu" "F.Mask" "F.Paste")
			(net "PE_TX4_DR5_P")
		)
		(pad "E18" smd rect
			(at 10.120122 -1.949958 90)
			(size 0.508 2.0066)
			(layers "F.Cu" "F.Mask" "F.Paste")
			(net "PE_TX4_DR5_N")
		)
		(pad "E19" smd rect
			(at 10.919968 -1.949958 90)
			(size 0.508 2.0066)
			(layers "F.Cu" "F.Mask" "F.Paste")
			(net "GND")
		)
		(pad "E20" smd rect
			(at 11.720068 -1.949958 90)
			(size 0.508 2.0066)
			(layers "F.Cu" "F.Mask" "F.Paste")
			(net "PE_RX4_DR5_P")
		)
		(pad "E21" smd rect
			(at 12.519914 -1.949958 90)
			(size 0.508 2.0066)
			(layers "F.Cu" "F.Mask" "F.Paste")
			(net "PE_RX4_DR5_N")
		)
		(pad "E22" smd rect
			(at 13.320014 -1.949958 90)
			(size 0.508 2.0066)
			(layers "F.Cu" "F.Mask" "F.Paste")
			(net "GND")
		)
		(pad "E23" smd rect
			(at 14.120114 -1.949958 90)
			(size 0.508 2.0066)
			(layers "F.Cu" "F.Mask" "F.Paste")
			(net "SCL_DR5_R")
		)
		(pad "E24" smd rect
			(at 14.91996 -1.949958 90)
			(size 0.508 2.0066)
			(layers "F.Cu" "F.Mask" "F.Paste")
			(net "SDA_DR5_R")
		)
		(pad "E25" smd rect
			(at 15.72006 -1.949958 90)
			(size 0.508 2.0066)
			(layers "F.Cu" "F.Mask" "F.Paste")
			(net "DUALPORTEN#5")
		)
		(pad "P1" smd rect
			(at -1.905 0.824992 90)
			(size 0.6604 2.0574)
			(layers "F.Cu" "F.Mask" "F.Paste")
			(net "Net_1146")
		)
		(pad "P2" smd rect
			(at -0.635 0.824992 90)
			(size 0.6604 2.0574)
			(layers "F.Cu" "F.Mask" "F.Paste")
			(net "Net_1145")
		)
		(pad "P3" smd rect
			(at 0.635 0.824992 90)
			(size 0.6604 2.0574)
			(layers "F.Cu" "F.Mask" "F.Paste")
			(net "Net_1144")
		)
		(pad "P4" smd rect
			(at 1.905 0.824992 90)
			(size 0.6604 2.0574)
			(layers "F.Cu" "F.Mask" "F.Paste")
			(net "SSD5_CLK0_OE_N")
		)
		(pad "P5" smd rect
			(at 3.175 0.824992 90)
			(size 0.6604 2.0574)
			(layers "F.Cu" "F.Mask" "F.Paste")
			(net "GND")
		)
		(pad "P6" smd rect
			(at 4.445 0.824992 90)
			(size 0.6604 2.0574)
			(layers "F.Cu" "F.Mask" "F.Paste")
			(net "GND")
		)
		(pad "P7" smd rect
			(at 5.715 0.824992 90)
			(size 0.6604 2.0574)
			(layers "F.Cu" "F.Mask" "F.Paste")
			(net "Net_90")
		)
		(pad "P8" smd rect
			(at 6.985 0.824992 90)
			(size 0.6604 2.0574)
			(layers "F.Cu" "F.Mask" "F.Paste")
			(net "Net_62")
		)
		(pad "P9" smd rect
			(at 8.255 0.824992 90)
			(size 0.6604 2.0574)
			(layers "F.Cu" "F.Mask" "F.Paste")
			(net "Net_76")
		)
		(pad "P10" smd rect
			(at 9.525 0.824992 90)
			(size 0.6604 2.0574)
			(layers "F.Cu" "F.Mask" "F.Paste")
			(net "SSD_PRSNT_NET5")
		)
		(pad "P11" smd rect
			(at 10.795 0.824992 90)
			(size 0.6604 2.0574)
			(layers "F.Cu" "F.Mask" "F.Paste")
			(net "SSD_ACT_DR5")
		)
		(pad "P12" smd rect
			(at 12.065 0.824992 90)
			(size 0.6604 2.0574)
			(layers "F.Cu" "F.Mask" "F.Paste")
			(net "GND")
		)
		(pad "P13" smd rect
			(at 13.335 0.824992 90)
			(size 0.6604 2.0574)
			(layers "F.Cu" "F.Mask" "F.Paste")
			(net "12V_PRECH_SSD5")
		)
		(pad "P14" smd rect
			(at 14.605 0.824992 90)
			(size 0.6604 2.0574)
			(layers "F.Cu" "F.Mask" "F.Paste")
			(net "P12V_SSD5")
		)
		(pad "P15" smd rect
			(at 15.875 0.824992 90)
			(size 0.6604 2.0574)
			(layers "F.Cu" "F.Mask" "F.Paste")
			(net "P12V_SSD5")
		)
		(pad "PTH1" thru_hole oval
			(at -21.999956 2.350008 90)
			(size 1.524 2.6162)
			(drill oval 0.8128 1.905)
			(layers "*.Cu" "*.Mask")
			(remove_unused_layers no)
			(net "Net_1155")
			(clearance 0.1524)
			(thermal_gap 0.1524)
		)
		(pad "PTH2" thru_hole oval
			(at 21.999956 2.350008 90)
			(size 1.524 2.6162)
			(drill oval 0.8128 1.905)
			(layers "*.Cu" "*.Mask")
			(remove_unused_layers no)
			(net "Net_1139")
			(clearance 0.1524)
			(thermal_gap 0.1524)
		)
		(pad "S1" smd rect
			(at -15.875 0.824992 90)
			(size 0.6604 2.0574)
			(layers "F.Cu" "F.Mask" "F.Paste")
			(net "GND")
		)
		(pad "S2" smd rect
			(at -14.605 0.824992 90)
			(size 0.6604 2.0574)
			(layers "F.Cu" "F.Mask" "F.Paste")
			(net "Net_1154")
		)
		(pad "S3" smd rect
			(at -13.335 0.824992 90)
			(size 0.6604 2.0574)
			(layers "F.Cu" "F.Mask" "F.Paste")
			(net "Net_1153")
		)
		(pad "S4" smd rect
			(at -12.065 0.824992 90)
			(size 0.6604 2.0574)
			(layers "F.Cu" "F.Mask" "F.Paste")
			(net "GND")
		)
		(pad "S5" smd rect
			(at -10.795 0.824992 90)
			(size 0.6604 2.0574)
			(layers "F.Cu" "F.Mask" "F.Paste")
			(net "Net_1152")
		)
		(pad "S6" smd rect
			(at -9.525 0.824992 90)
			(size 0.6604 2.0574)
			(layers "F.Cu" "F.Mask" "F.Paste")
			(net "Net_1151")
		)
		(pad "S7" smd rect
			(at -8.255 0.824992 90)
			(size 0.6604 2.0574)
			(layers "F.Cu" "F.Mask" "F.Paste")
			(net "GND")
		)
		(pad "S8" smd rect
			(at -7.480046 -1.949958 90)
			(size 0.508 2.0066)
			(layers "F.Cu" "F.Mask" "F.Paste")
			(net "GND")
		)
		(pad "S9" smd rect
			(at -6.679946 -1.949958 90)
			(size 0.508 2.0066)
			(layers "F.Cu" "F.Mask" "F.Paste")
			(net "Net_1149")
		)
		(pad "S10" smd rect
			(at -5.8801 -1.949958 90)
			(size 0.508 2.0066)
			(layers "F.Cu" "F.Mask" "F.Paste")
			(net "Net_1148")
		)
		(pad "S11" smd rect
			(at -5.08 -1.949958 90)
			(size 0.508 2.0066)
			(layers "F.Cu" "F.Mask" "F.Paste")
			(net "GND")
		)
		(pad "S12" smd rect
			(at -4.2799 -1.949958 90)
			(size 0.508 2.0066)
			(layers "F.Cu" "F.Mask" "F.Paste")
			(net "Net_1147")
		)
		(pad "S13" smd rect
			(at -3.480054 -1.949958 90)
			(size 0.508 2.0066)
			(layers "F.Cu" "F.Mask" "F.Paste")
			(net "Net_1142")
		)
		(pad "S14" smd rect
			(at -2.679954 -1.949958 90)
			(size 0.508 2.0066)
			(layers "F.Cu" "F.Mask" "F.Paste")
			(net "GND")
		)
		(pad "S15" smd rect
			(at -1.880108 -1.949958 90)
			(size 0.508 2.0066)
			(layers "F.Cu" "F.Mask" "F.Paste")
			(net "Net_1141")
		)
		(pad "S16" smd rect
			(at -1.080008 -1.949958 90)
			(size 0.508 2.0066)
			(layers "F.Cu" "F.Mask" "F.Paste")
			(net "GND")
		)
		(pad "S17" smd rect
			(at -0.279908 -1.949958 90)
			(size 0.508 2.0066)
			(layers "F.Cu" "F.Mask" "F.Paste")
			(net "PE_TX2_DR5_P")
		)
		(pad "S18" smd rect
			(at 0.519938 -1.949958 90)
			(size 0.508 2.0066)
			(layers "F.Cu" "F.Mask" "F.Paste")
			(net "PE_TX2_DR5_N")
		)
		(pad "S19" smd rect
			(at 1.320038 -1.949958 90)
			(size 0.508 2.0066)
			(layers "F.Cu" "F.Mask" "F.Paste")
			(net "GND")
		)
		(pad "S20" smd rect
			(at 2.119884 -1.949958 90)
			(size 0.508 2.0066)
			(layers "F.Cu" "F.Mask" "F.Paste")
			(net "PE_RX2_DR5_P")
		)
		(pad "S21" smd rect
			(at 2.919984 -1.949958 90)
			(size 0.508 2.0066)
			(layers "F.Cu" "F.Mask" "F.Paste")
			(net "PE_RX2_DR5_N")
		)
		(pad "S22" smd rect
			(at 3.720084 -1.949958 90)
			(size 0.508 2.0066)
			(layers "F.Cu" "F.Mask" "F.Paste")
			(net "GND")
		)
		(pad "S23" smd rect
			(at 4.51993 -1.949958 90)
			(size 0.508 2.0066)
			(layers "F.Cu" "F.Mask" "F.Paste")
			(net "PE_TX3_DR5_P")
		)
		(pad "S24" smd rect
			(at 5.32003 -1.949958 90)
			(size 0.508 2.0066)
			(layers "F.Cu" "F.Mask" "F.Paste")
			(net "PE_TX3_DR5_N")
		)
		(pad "S25" smd rect
			(at 6.119876 -1.949958 90)
			(size 0.508 2.0066)
			(layers "F.Cu" "F.Mask" "F.Paste")
			(net "GND")
		)
		(pad "S26" smd rect
			(at 6.919976 -1.949958 90)
			(size 0.508 2.0066)
			(layers "F.Cu" "F.Mask" "F.Paste")
			(net "PE_RX3_DR5_P")
		)
		(pad "S27" smd rect
			(at 7.720076 -1.949958 90)
			(size 0.508 2.0066)
			(layers "F.Cu" "F.Mask" "F.Paste")
			(net "PE_RX3_DR5_N")
		)
		(pad "S28" smd rect
			(at 8.519922 -1.949958 90)
			(size 0.508 2.0066)
			(layers "F.Cu" "F.Mask" "F.Paste")
			(net "GND")
		)
		(zone
			(layers "F.Cu" "B.Cu" "In1.Cu" "In2.Cu" "In3.Cu" "In4.Cu" "In5.Cu" "In6.Cu")
			(hatch none 0.5)
			(connect_pads
				(clearance 0)
			)
			(min_thickness 0.25)
			(keepout
				(tracks not_allowed)
				(vias allowed)
				(pads allowed)
				(copperpour not_allowed)
				(footprints allowed)
			)
			(placement
				(enabled no)
				(sheetname "")
			)
			(fill
				(thermal_gap 0.5)
				(thermal_bridge_width 0.5)
				(island_removal_mode 0)
			)
			(polygon
				(pts
					(arc
						(start 42.381932 -498.670072)
						(mid 39.918132 -498.670072)
						(end 42.381932 -498.670072)
					)
				)
			)
		)
		(zone
			(layers "F.Cu" "B.Cu" "In1.Cu" "In2.Cu" "In3.Cu" "In4.Cu" "In5.Cu" "In6.Cu")
			(hatch none 0.5)
			(connect_pads
				(clearance 0)
			)
			(min_thickness 0.25)
			(keepout
				(tracks not_allowed)
				(vias allowed)
				(pads allowed)
				(copperpour not_allowed)
				(footprints allowed)
			)
			(placement
				(enabled no)
				(sheetname "")
			)
			(fill
				(thermal_gap 0.5)
				(thermal_bridge_width 0.5)
				(island_removal_mode 0)
			)
			(polygon
				(pts
					(arc
						(start 42.381932 -460.670148)
						(mid 39.918132 -460.670148)
						(end 42.381932 -460.670148)
					)
				)
			)
		)
	)
)
